(kicad_pcb
	(version 20260206)
	(generator "pcbnew")
	(generator_version "10.0")
	(general
		(thickness 1.6)
		(legacy_teardrops no)
	)
	(paper "A4")
	(title_block
		(title "baseboard — 13948-1b.1110WZS1818.brd")
		(comment 1 "Honey Badger (Wiwynn) / footprints 398-404 of 2523")
	)
	(layers
		(0 "F.Cu" signal "TOP")
		(4 "In1.Cu" signal "L2GND")
		(6 "In2.Cu" signal "L3")
		(8 "In3.Cu" signal "L4VCC")
		(10 "In4.Cu" signal "L5VCC")
		(12 "In5.Cu" signal "L6")
		(14 "In6.Cu" signal "L7GND")
		(2 "B.Cu" signal "BOTTOM")
		(9 "F.Adhes" user "F.Adhesive")
		(11 "B.Adhes" user "B.Adhesive")
		(13 "F.Paste" user "Package Geometry/Pastemask Top")
		(15 "B.Paste" user "Package Geometry/Pastemask Bottom")
		(5 "F.SilkS" user "Ref Des/Silkscreen Top")
		(7 "B.SilkS" user "Ref Des/Silkscreen Bottom")
		(1 "F.Mask" user "Board Geometry/Soldermask Top")
		(3 "B.Mask" user "Board Geometry/Soldermask Bottom")
		(17 "Dwgs.User" user "User.Drawings")
		(19 "Cmts.User" user "User.Comments")
		(21 "Eco1.User" user "User.Eco1")
		(23 "Eco2.User" user "User.Eco2")
		(25 "Edge.Cuts" user "Board Geometry/Outline")
		(27 "Margin" user)
		(31 "F.CrtYd" user "Package Geometry/Place Bound Top")
		(29 "B.CrtYd" user "Package Geometry/Place Bound Bottom")
		(35 "F.Fab" user "Ref Des/Assembly Top")
		(33 "B.Fab" user "Ref Des/Assembly Bottom")
	)
	(footprint ""
		(layer "F.Cu")
		(at 29.160216 -202.87488 -90)
		(property "Reference" "U17"
			(at 0 0 270)
			(layer "F.SilkS")
			(hide yes)
			(effects
				(font
					(size 1.27 1.27)
				)
			)
		)
		(property "Value" "ADS1015IDGSR-GP"
			(at 0 -11.1252 270)
			(unlocked yes)
			(layer "F.Fab")
			(hide yes)
			(effects
				(font
					(size 1.016 1.016)
					(thickness 0.1524)
				)
			)
		)
		(property "Device Type" "MSOP10H44"
			(at 0 -12.6492 270)
			(unlocked yes)
			(layer "F.Fab")
			(hide yes)
			(effects
				(font
					(size 1.016 1.016)
					(thickness 0.1524)
				)
			)
		)
		(duplicate_pad_numbers_are_jumpers no)
		(fp_line
			(start -2.0066 1.016)
			(end -2.0066 -1.016)
			(stroke
				(width 0.1524)
				(type default)
			)
			(layer "F.SilkS")
		)
		(fp_line
			(start -1.8288 1.016)
			(end -1.8288 3.048)
			(stroke
				(width 0.508)
				(type default)
			)
			(layer "F.SilkS")
		)
		(fp_line
			(start 1.143 1.016)
			(end -2.0066 1.016)
			(stroke
				(width 0.1524)
				(type default)
			)
			(layer "F.SilkS")
		)
		(fp_line
			(start -1.5748 0)
			(end -1.9558 0.381)
			(stroke
				(width 0.1524)
				(type default)
			)
			(layer "F.SilkS")
		)
		(fp_line
			(start -1.5748 0)
			(end -1.9558 -0.381)
			(stroke
				(width 0.1524)
				(type default)
			)
			(layer "F.SilkS")
		)
		(fp_line
			(start -2.0066 -1.016)
			(end 1.143 -1.016)
			(stroke
				(width 0.1524)
				(type default)
			)
			(layer "F.SilkS")
		)
		(fp_line
			(start 1.143 -1.016)
			(end 1.143 1.016)
			(stroke
				(width 0.1524)
				(type default)
			)
			(layer "F.SilkS")
		)
		(fp_poly
			(pts
				(xy -2.0828 3.3401) (xy 2.0828 3.3401) (xy 2.0828 -3.3401) (xy -2.0828 -3.3401)
			)
			(stroke
				(width 0)
				(type default)
			)
			(fill no)
			(layer "F.CrtYd")
		)
		(fp_poly
			(pts
				(xy -2.0828 3.3401) (xy 2.0828 3.3401) (xy 2.0828 -3.3401) (xy -2.0828 -3.3401)
			)
			(stroke
				(width 0)
				(type default)
			)
			(fill no)
			(layer "F.Fab")
		)
		(pad "1" smd rect
			(at -0.99949 2.0701 270)
			(size 0.3048 1.524)
			(layers "F.Cu" "F.Mask" "F.Paste")
			(net "VOL_SEN_ADDR_U17")
		)
		(pad "2" smd rect
			(at -0.50038 2.0701 270)
			(size 0.3048 1.524)
			(layers "F.Cu" "F.Mask" "F.Paste")
			(net "VOL_SEN_ALERT_U17")
		)
		(pad "3" smd rect
			(at 0 2.0701 270)
			(size 0.3048 1.524)
			(layers "F.Cu" "F.Mask" "F.Paste")
			(net "GND")
		)
		(pad "4" smd rect
			(at 0.50038 2.0701 270)
			(size 0.3048 1.524)
			(layers "F.Cu" "F.Mask" "F.Paste")
			(net "P0V9_E_SENSE")
		)
		(pad "5" smd rect
			(at 0.99949 2.0701 270)
			(size 0.3048 1.524)
			(layers "F.Cu" "F.Mask" "F.Paste")
			(net "P0V955_C_SENSE")
		)
		(pad "6" smd rect
			(at 0.99949 -2.0701 270)
			(size 0.3048 1.524)
			(layers "F.Cu" "F.Mask" "F.Paste")
			(net "P1V5_E_SENSE")
		)
		(pad "7" smd rect
			(at 0.50038 -2.0701 270)
			(size 0.3048 1.524)
			(layers "F.Cu" "F.Mask" "F.Paste")
			(net "P1V5_C_SENSE")
		)
		(pad "8" smd rect
			(at 0 -2.0701 270)
			(size 0.3048 1.524)
			(layers "F.Cu" "F.Mask" "F.Paste")
			(net "P3V3_STBY")
		)
		(pad "9" smd rect
			(at -0.50038 -2.0701 270)
			(size 0.3048 1.524)
			(layers "F.Cu" "F.Mask" "F.Paste")
			(net "VOL_SEN_SDA_U17")
		)
		(pad "10" smd rect
			(at -0.99949 -2.0701 270)
			(size 0.3048 1.524)
			(layers "F.Cu" "F.Mask" "F.Paste")
			(net "VOL_SEN_SCL_U17")
		)
	)
	(footprint ""
		(layer "F.Cu")
		(at 152.019 -50.927 90)
		(property "Reference" "SR697"
			(at 0 0 90)
			(layer "F.SilkS")
			(hide yes)
			(effects
				(font
					(size 1.27 1.27)
				)
			)
		)
		(property "Value" "10KR2F-2-GP"
			(at 0.064008 -3.993896 90)
			(unlocked yes)
			(layer "F.Fab")
			(hide yes)
			(effects
				(font
					(size 1.016 1.016)
					(thickness 0.1524)
				)
			)
		)
		(property "Device Type" "R402H16"
			(at 0.064008 -5.517896 90)
			(unlocked yes)
			(layer "F.Fab")
			(hide yes)
			(effects
				(font
					(size 1.016 1.016)
					(thickness 0.1524)
				)
			)
		)
		(duplicate_pad_numbers_are_jumpers no)
		(fp_line
			(start 0.508 -0.9398)
			(end -0.508 -0.9398)
			(stroke
				(width 0.1524)
				(type default)
			)
			(layer "F.SilkS")
		)
		(fp_line
			(start -0.508 -0.9398)
			(end -0.508 0.9398)
			(stroke
				(width 0.1524)
				(type default)
			)
			(layer "F.SilkS")
		)
		(fp_rect
			(start -0.508 0.9398)
			(end 0.508 -0.9398)
			(stroke
				(width 0)
				(type default)
			)
			(fill no)
			(layer "F.CrtYd")
		)
		(fp_rect
			(start -0.508 0.9398)
			(end 0.508 -0.9398)
			(stroke
				(width 0)
				(type default)
			)
			(fill no)
			(layer "F.Fab")
		)
		(pad "1" smd custom
			(at 0 -0.4445 90)
			(size 0.1397 0.1397)
			(layers "F.Cu" "F.Mask" "F.Paste")
			(net "XM_ADDR_2")
			(options
				(clearance outline)
				(anchor circle)
			)
			(primitives
				(gr_poly
					(pts
						(arc
							(start -0.1778 -0.2794)
							(mid -0.249642 -0.249642)
							(end -0.2794 -0.1778)
						)
						(arc
							(start -0.2794 0.1778)
							(mid -0.249642 0.249642)
							(end -0.1778 0.2794)
						)
						(arc
							(start 0.1778 0.2794)
							(mid 0.249642 0.249642)
							(end 0.2794 0.1778)
						)
						(arc
							(start 0.2794 -0.1778)
							(mid 0.249642 -0.249642)
							(end 0.1778 -0.2794)
						)
					)
					(width 0)
					(fill yes)
				)
			)
		)
		(pad "2" smd custom
			(at 0 0.4445 90)
			(size 0.1397 0.1397)
			(layers "F.Cu" "F.Mask" "F.Paste")
			(net "GND")
			(options
				(clearance outline)
				(anchor circle)
			)
			(primitives
				(gr_poly
					(pts
						(arc
							(start -0.1778 -0.2794)
							(mid -0.249642 -0.249642)
							(end -0.2794 -0.1778)
						)
						(arc
							(start -0.2794 0.1778)
							(mid -0.249642 0.249642)
							(end -0.1778 0.2794)
						)
						(arc
							(start 0.1778 0.2794)
							(mid 0.249642 0.249642)
							(end 0.2794 0.1778)
						)
						(arc
							(start 0.2794 -0.1778)
							(mid 0.249642 -0.249642)
							(end 0.1778 -0.2794)
						)
					)
					(width 0)
					(fill yes)
				)
			)
		)
	)
	(footprint ""
		(layer "F.Cu")
		(at 140.88237 -88.411812 180)
		(property "Reference" "U135"
			(at 0 0 180)
			(layer "F.SilkS")
			(hide yes)
			(effects
				(font
					(size 1.27 1.27)
				)
			)
		)
		(property "Value" "TMP75AIDGKR-GP"
			(at -0.1143 -9.1948 180)
			(unlocked yes)
			(layer "F.Fab")
			(hide yes)
			(effects
				(font
					(size 1.016 1.016)
					(thickness 0.1524)
				)
			)
		)
		(property "Device Type" "MSOP8-1H44"
			(at -0.1143 -10.795 180)
			(unlocked yes)
			(layer "F.Fab")
			(hide yes)
			(effects
				(font
					(size 1.016 1.016)
					(thickness 0.1524)
				)
			)
		)
		(duplicate_pad_numbers_are_jumpers no)
		(fp_line
			(start 1.0795 1.016)
			(end 1.0795 -1.016)
			(stroke
				(width 0.1524)
				(type default)
			)
			(layer "F.SilkS")
		)
		(fp_line
			(start 1.0795 -1.016)
			(end -1.9558 -1.016)
			(stroke
				(width 0.1524)
				(type default)
			)
			(layer "F.SilkS")
		)
		(fp_line
			(start -1.4478 -0.0381)
			(end -1.9558 0.4699)
			(stroke
				(width 0.1524)
				(type default)
			)
			(layer "F.SilkS")
		)
		(fp_line
			(start -1.778 1.0922)
			(end -1.778 3.048)
			(stroke
				(width 0.508)
				(type default)
			)
			(layer "F.SilkS")
		)
		(fp_line
			(start -1.9558 1.016)
			(end 1.0795 1.016)
			(stroke
				(width 0.1524)
				(type default)
			)
			(layer "F.SilkS")
		)
		(fp_line
			(start -1.9558 -0.5461)
			(end -1.4478 -0.0381)
			(stroke
				(width 0.1524)
				(type default)
			)
			(layer "F.SilkS")
		)
		(fp_line
			(start -1.9558 -1.016)
			(end -1.9558 1.016)
			(stroke
				(width 0.1524)
				(type default)
			)
			(layer "F.SilkS")
		)
		(fp_poly
			(pts
				(xy -1.1557 -1.016) (xy -1.1557 1.016) (xy 1.1557 1.016) (xy 1.1557 -1.016)
			)
			(stroke
				(width 0)
				(type default)
			)
			(fill yes)
			(layer "F.SilkS")
		)
		(fp_rect
			(start -1.4986 2.4511)
			(end 1.4986 -2.4511)
			(stroke
				(width 0)
				(type default)
			)
			(fill no)
			(layer "F.CrtYd")
		)
		(fp_poly
			(pts
				(xy -2.032 3.302) (xy -2.032 -3.302) (xy 2.032 -3.302) (xy 2.032 -2.1209) (xy 1.4986 -2.1209) (xy 1.4986 -2.4511)
				(xy -1.4986 -2.4511) (xy -1.4986 2.4511) (xy 1.4986 2.4511) (xy 1.4986 -2.1082) (xy 2.032 -2.1082)
				(xy 2.032 3.302)
			)
			(stroke
				(width 0)
				(type default)
			)
			(fill no)
			(layer "F.CrtYd")
		)
		(fp_rect
			(start -2.032 3.302)
			(end 2.032 -3.302)
			(stroke
				(width 0)
				(type default)
			)
			(fill no)
			(layer "F.Fab")
		)
		(pad "1" smd rect
			(at -0.97536 2.05486 180)
			(size 0.3556 1.524)
			(layers "F.Cu" "F.Mask" "F.Paste")
			(net "TEMP_3_SDA")
		)
		(pad "2" smd rect
			(at -0.32512 2.05486 180)
			(size 0.3556 1.524)
			(layers "F.Cu" "F.Mask" "F.Paste")
			(net "TEMP_3_SCL")
		)
		(pad "3" smd rect
			(at 0.32512 2.05486 180)
			(size 0.3556 1.524)
			(layers "F.Cu" "F.Mask" "F.Paste")
			(net "TEMP_3_ALERT")
		)
		(pad "4" smd rect
			(at 0.97536 2.05486 180)
			(size 0.3556 1.524)
			(layers "F.Cu" "F.Mask" "F.Paste")
			(net "GND")
		)
		(pad "5" smd rect
			(at 0.97536 -2.05486 180)
			(size 0.3556 1.524)
			(layers "F.Cu" "F.Mask" "F.Paste")
			(net "TEMP_3_A2")
		)
		(pad "6" smd rect
			(at 0.32512 -2.05486 180)
			(size 0.3556 1.524)
			(layers "F.Cu" "F.Mask" "F.Paste")
			(net "TEMP_3_A1")
		)
		(pad "7" smd rect
			(at -0.32512 -2.05486 180)
			(size 0.3556 1.524)
			(layers "F.Cu" "F.Mask" "F.Paste")
			(net "TEMP_3_A0")
		)
		(pad "8" smd rect
			(at -0.97536 -2.05486 180)
			(size 0.3556 1.524)
			(layers "F.Cu" "F.Mask" "F.Paste")
			(net "P3V3_STBY")
		)
	)
	(footprint ""
		(layer "F.Cu")
		(at 309.871872 -200.859136 90)
		(property "Reference" "TP83"
			(at 0 0 90)
			(layer "F.SilkS")
			(hide yes)
			(effects
				(font
					(size 1.27 1.27)
				)
			)
		)
		(property "Value" "TPAD32-GP"
			(at 0 -3.166364 90)
			(unlocked yes)
			(layer "F.Fab")
			(hide yes)
			(effects
				(font
					(size 1.016 1.016)
					(thickness 0.1524)
				)
			)
		)
		(property "Device Type" "TPAD32"
			(at 0 -4.690618 90)
			(unlocked yes)
			(layer "F.Fab")
			(hide yes)
			(effects
				(font
					(size 1.016 1.016)
					(thickness 0.1524)
				)
			)
		)
		(duplicate_pad_numbers_are_jumpers no)
		(fp_poly
			(pts
				(arc
					(start 0 0.4064)
					(mid 0 -0.4064)
					(end 0 0.4064)
				)
			)
			(stroke
				(width 0)
				(type default)
			)
			(fill no)
			(layer "F.CrtYd")
		)
		(fp_poly
			(pts
				(arc
					(start 0 0.7112)
					(mid 0 -0.7112)
					(end 0 0.7112)
				)
			)
			(stroke
				(width 0)
				(type default)
			)
			(fill no)
			(layer "F.Fab")
		)
		(pad "1" smd circle
			(at 0 0 90)
			(size 0.8128 0.8128)
			(layers "F.Cu" "F.Mask" "F.Paste")
			(net "LED_DR_RESET#")
		)
	)
	(footprint ""
		(layer "F.Cu")
		(at 300.228 -91.948 180)
		(property "Reference" "R5308"
			(at 0 0 180)
			(layer "F.SilkS")
			(hide yes)
			(effects
				(font
					(size 1.27 1.27)
				)
			)
		)
		(property "Value" "0R2J-2-GP"
			(at 0.064008 -3.993896 180)
			(unlocked yes)
			(layer "F.Fab")
			(hide yes)
			(effects
				(font
					(size 1.016 1.016)
					(thickness 0.1524)
				)
			)
		)
		(property "Device Type" "R402H16"
			(at 0.064008 -5.517896 180)
			(unlocked yes)
			(layer "F.Fab")
			(hide yes)
			(effects
				(font
					(size 1.016 1.016)
					(thickness 0.1524)
				)
			)
		)
		(duplicate_pad_numbers_are_jumpers no)
		(fp_line
			(start 0.508 -0.9398)
			(end -0.508 -0.9398)
			(stroke
				(width 0.1524)
				(type default)
			)
			(layer "F.SilkS")
		)
		(fp_line
			(start -0.508 -0.9398)
			(end -0.508 0.9398)
			(stroke
				(width 0.1524)
				(type default)
			)
			(layer "F.SilkS")
		)
		(fp_rect
			(start -0.508 0.9398)
			(end 0.508 -0.9398)
			(stroke
				(width 0)
				(type default)
			)
			(fill no)
			(layer "F.CrtYd")
		)
		(fp_rect
			(start -0.508 0.9398)
			(end 0.508 -0.9398)
			(stroke
				(width 0)
				(type default)
			)
			(fill no)
			(layer "F.Fab")
		)
		(pad "1" smd custom
			(at 0 -0.4445 180)
			(size 0.1397 0.1397)
			(layers "F.Cu" "F.Mask" "F.Paste")
			(net "BMC_I2C_SDA_10")
			(options
				(clearance outline)
				(anchor circle)
			)
			(primitives
				(gr_poly
					(pts
						(arc
							(start -0.1778 -0.2794)
							(mid -0.249642 -0.249642)
							(end -0.2794 -0.1778)
						)
						(arc
							(start -0.2794 0.1778)
							(mid -0.249642 0.249642)
							(end -0.1778 0.2794)
						)
						(arc
							(start 0.1778 0.2794)
							(mid 0.249642 0.249642)
							(end 0.2794 0.1778)
						)
						(arc
							(start 0.2794 -0.1778)
							(mid 0.249642 -0.249642)
							(end 0.1778 -0.2794)
						)
					)
					(width 0)
					(fill yes)
				)
			)
		)
		(pad "2" smd custom
			(at 0 0.4445 180)
			(size 0.1397 0.1397)
			(layers "F.Cu" "F.Mask" "F.Paste")
			(net "TEMP_2_SDA")
			(options
				(clearance outline)
				(anchor circle)
			)
			(primitives
				(gr_poly
					(pts
						(arc
							(start -0.1778 -0.2794)
							(mid -0.249642 -0.249642)
							(end -0.2794 -0.1778)
						)
						(arc
							(start -0.2794 0.1778)
							(mid -0.249642 0.249642)
							(end -0.1778 0.2794)
						)
						(arc
							(start 0.1778 0.2794)
							(mid 0.249642 0.249642)
							(end 0.2794 0.1778)
						)
						(arc
							(start 0.2794 -0.1778)
							(mid 0.249642 -0.249642)
							(end 0.1778 -0.2794)
						)
					)
					(width 0)
					(fill yes)
				)
			)
		)
	)
	(footprint ""
		(layer "F.Cu")
		(at 95.70847 -107.188 -90)
		(property "Reference" "SR736"
			(at 0 0 270)
			(layer "F.SilkS")
			(hide yes)
			(effects
				(font
					(size 1.27 1.27)
				)
			)
		)
		(property "Value" "2K2R2F-GP"
			(at 0.064008 -3.993896 270)
			(unlocked yes)
			(layer "F.Fab")
			(hide yes)
			(effects
				(font
					(size 1.016 1.016)
					(thickness 0.1524)
				)
			)
		)
		(property "Device Type" "R402H16"
			(at 0.064008 -5.517896 270)
			(unlocked yes)
			(layer "F.Fab")
			(hide yes)
			(effects
				(font
					(size 1.016 1.016)
					(thickness 0.1524)
				)
			)
		)
		(duplicate_pad_numbers_are_jumpers no)
		(fp_line
			(start -0.508 -0.9398)
			(end -0.508 0.9398)
			(stroke
				(width 0.1524)
				(type default)
			)
			(layer "F.SilkS")
		)
		(fp_line
			(start 0.508 -0.9398)
			(end -0.508 -0.9398)
			(stroke
				(width 0.1524)
				(type default)
			)
			(layer "F.SilkS")
		)
		(fp_rect
			(start -0.508 0.9398)
			(end 0.508 -0.9398)
			(stroke
				(width 0)
				(type default)
			)
			(fill no)
			(layer "F.CrtYd")
		)
		(fp_rect
			(start -0.508 0.9398)
			(end 0.508 -0.9398)
			(stroke
				(width 0)
				(type default)
			)
			(fill no)
			(layer "F.Fab")
		)
		(pad "1" smd custom
			(at 0 -0.4445 270)
			(size 0.1397 0.1397)
			(layers "F.Cu" "F.Mask" "F.Paste")
			(net "EXP_I2C_SCL_4")
			(options
				(clearance outline)
				(anchor circle)
			)
			(primitives
				(gr_poly
					(pts
						(arc
							(start -0.1778 -0.2794)
							(mid -0.249642 -0.249642)
							(end -0.2794 -0.1778)
						)
						(arc
							(start -0.2794 0.1778)
							(mid -0.249642 0.249642)
							(end -0.1778 0.2794)
						)
						(arc
							(start 0.1778 0.2794)
							(mid 0.249642 0.249642)
							(end 0.2794 0.1778)
						)
						(arc
							(start 0.2794 -0.1778)
							(mid 0.249642 -0.249642)
							(end 0.1778 -0.2794)
						)
					)
					(width 0)
					(fill yes)
				)
			)
		)
		(pad "2" smd custom
			(at 0 0.4445 270)
			(size 0.1397 0.1397)
			(layers "F.Cu" "F.Mask" "F.Paste")
			(net "P1V8_E")
			(options
				(clearance outline)
				(anchor circle)
			)
			(primitives
				(gr_poly
					(pts
						(arc
							(start -0.1778 -0.2794)
							(mid -0.249642 -0.249642)
							(end -0.2794 -0.1778)
						)
						(arc
							(start -0.2794 0.1778)
							(mid -0.249642 0.249642)
							(end -0.1778 0.2794)
						)
						(arc
							(start 0.1778 0.2794)
							(mid 0.249642 0.249642)
							(end 0.2794 0.1778)
						)
						(arc
							(start 0.2794 -0.1778)
							(mid 0.249642 -0.249642)
							(end 0.1778 -0.2794)
						)
					)
					(width 0)
					(fill yes)
				)
			)
		)
	)
	(footprint ""
		(layer "F.Cu")
		(at 266.065 -176.022 90)
		(property "Reference" "R447"
			(at 0 0 90)
			(layer "F.SilkS")
			(hide yes)
			(effects
				(font
					(size 1.27 1.27)
				)
			)
		)
		(property "Value" "10KR2F-2-GP"
			(at 0.064008 -3.993896 90)
			(unlocked yes)
			(layer "F.Fab")
			(hide yes)
			(effects
				(font
					(size 1.016 1.016)
					(thickness 0.1524)
				)
			)
		)
		(property "Device Type" "R402H16"
			(at 0.064008 -5.517896 90)
			(unlocked yes)
			(layer "F.Fab")
			(hide yes)
			(effects
				(font
					(size 1.016 1.016)
					(thickness 0.1524)
				)
			)
		)
		(duplicate_pad_numbers_are_jumpers no)
		(fp_line
			(start 0.508 -0.9398)
			(end -0.508 -0.9398)
			(stroke
				(width 0.1524)
				(type default)
			)
			(layer "F.SilkS")
		)
		(fp_line
			(start -0.508 -0.9398)
			(end -0.508 0.9398)
			(stroke
				(width 0.1524)
				(type default)
			)
			(layer "F.SilkS")
		)
		(fp_rect
			(start -0.508 0.9398)
			(end 0.508 -0.9398)
			(stroke
				(width 0)
				(type default)
			)
			(fill no)
			(layer "F.CrtYd")
		)
		(fp_rect
			(start -0.508 0.9398)
			(end 0.508 -0.9398)
			(stroke
				(width 0)
				(type default)
			)
			(fill no)
			(layer "F.Fab")
		)
		(pad "1" smd custom
			(at 0 -0.4445 90)
			(size 0.1397 0.1397)
			(layers "F.Cu" "F.Mask" "F.Paste")
			(net "P3V3_STBY")
			(options
				(clearance outline)
				(anchor circle)
			)
			(primitives
				(gr_poly
					(pts
						(arc
							(start -0.1778 -0.2794)
							(mid -0.249642 -0.249642)
							(end -0.2794 -0.1778)
						)
						(arc
							(start -0.2794 0.1778)
							(mid -0.249642 0.249642)
							(end -0.1778 0.2794)
						)
						(arc
							(start 0.1778 0.2794)
							(mid 0.249642 0.249642)
							(end 0.2794 0.1778)
						)
						(arc
							(start 0.2794 -0.1778)
							(mid 0.249642 -0.249642)
							(end 0.1778 -0.2794)
						)
					)
					(width 0)
					(fill yes)
				)
			)
		)
		(pad "2" smd custom
			(at 0 0.4445 90)
			(size 0.1397 0.1397)
			(layers "F.Cu" "F.Mask" "F.Paste")
			(net "BMC_SALT3")
			(options
				(clearance outline)
				(anchor circle)
			)
			(primitives
				(gr_poly
					(pts
						(arc
							(start -0.1778 -0.2794)
							(mid -0.249642 -0.249642)
							(end -0.2794 -0.1778)
						)
						(arc
							(start -0.2794 0.1778)
							(mid -0.249642 0.249642)
							(end -0.1778 0.2794)
						)
						(arc
							(start 0.1778 0.2794)
							(mid 0.249642 0.249642)
							(end 0.2794 0.1778)
						)
						(arc
							(start 0.2794 -0.1778)
							(mid 0.249642 -0.249642)
							(end 0.1778 -0.2794)
						)
					)
					(width 0)
					(fill yes)
				)
			)
		)
	)
)
